# T6G (Grand Teton) — schematic netlist excerpt (pin names and nets, part order shuffled) for the footprints in the layout excerpt that follows; sources: Cadence DE-HDL packaged netlist, KiCad conversion of 04192023_DAF0TMB3IC0_F0TG_MB_C_brd_V02_OCP.brd

PC143  Q_CAP  2.2UF 10V 10% X6S  pkg C0402  page 205 : A = PVDDIO_P0_VCC1 ; B = GND
R6170  Q_RES  1K 1% CHIP  pkg 0402LF  page 112 : A = FM_P2E_BUF2_VODA_DB ; B = GND
C1538  Q_CAP_DIFFBUS  DIFF BUS_0.22UF 6.3V 20% X6S  pkg C0201  page 67 : \1\ = P5E_CPU1_P3_TX_C_DN<4> ; \2\ = P5E_CPU1_P3_TX_DN<4>

(kicad_pcb
	(version 20260206)
	(generator "pcbnew")
	(generator_version "10.0")
	(general
		(thickness 1.6)
		(legacy_teardrops no)
	)
	(paper "A4")
	(title_block
		(title "04192023_DAF0TMB3IC0_F0TG_MB_C_brd_V02_OCP.brd")
		(comment 1 "Grand Teton / footprints 1302-1304 of 8354")
	)
	(layers
		(0 "F.Cu" signal "TOP")
		(4 "In1.Cu" signal "GND")
		(6 "In2.Cu" signal "IN1")
		(8 "In3.Cu" signal "GND1")
		(10 "In4.Cu" signal "IN2")
		(12 "In5.Cu" signal "GND2")
		(14 "In6.Cu" signal "IN3")
		(16 "In7.Cu" signal "GND3")
		(18 "In8.Cu" signal "VCC")
		(20 "In9.Cu" signal "VCC1")
		(22 "In10.Cu" signal "GND4")
		(24 "In11.Cu" signal "IN4")
		(26 "In12.Cu" signal "GND5")
		(28 "In13.Cu" signal "IN5")
		(30 "In14.Cu" signal "GND6")
		(32 "In15.Cu" signal "IN6")
		(34 "In16.Cu" signal "GND7")
		(2 "B.Cu" signal "BOTTOM")
		(9 "F.Adhes" user "F.Adhesive")
		(11 "B.Adhes" user "B.Adhesive")
		(13 "F.Paste" user "Package Geometry/Pastemask Top")
		(15 "B.Paste" user "Package Geometry/Pastemask Bottom")
		(5 "F.SilkS" user "Ref Des/Silkscreen Top")
		(7 "B.SilkS" user "Ref Des/Silkscreen Bottom")
		(1 "F.Mask" user "Board Geometry/Soldermask Top")
		(3 "B.Mask" user "Board Geometry/Soldermask Bottom")
		(17 "Dwgs.User" user "User.Drawings")
		(19 "Cmts.User" user "User.Comments")
		(21 "Eco1.User" user "User.Eco1")
		(23 "Eco2.User" user "User.Eco2")
		(25 "Edge.Cuts" user "Board Geometry/Outline")
		(27 "Margin" user)
		(31 "F.CrtYd" user "Package Geometry/Place Bound Top")
		(29 "B.CrtYd" user "Package Geometry/Place Bound Bottom")
		(35 "F.Fab" user "Ref Des/Assembly Top")
		(33 "B.Fab" user "Ref Des/Assembly Bottom")
	)
	(footprint ""
		(layer "F.Cu")
		(at 296.681906 -349.381572 90)
		(property "Reference" "PC143"
			(at 0 0 90)
			(layer "F.SilkS")
			(hide yes)
			(effects
				(font
					(size 1.27 1.27)
				)
			)
		)
		(property "Value" ""
			(at 0 0 90)
			(layer "F.Fab")
			(effects
				(font
					(size 1.27 1.27)
				)
			)
		)
		(duplicate_pad_numbers_are_jumpers no)
		(fp_line
			(start 0.7874 -0.4064)
			(end 0.7874 0.4064)
			(stroke
				(width 0.1524)
				(type default)
			)
			(layer "F.SilkS")
		)
		(fp_line
			(start -0.7874 -0.4064)
			(end 0.7874 -0.4064)
			(stroke
				(width 0.1524)
				(type default)
			)
			(layer "F.SilkS")
		)
		(fp_line
			(start 0.7874 0.4064)
			(end 0.401828 0.4064)
			(stroke
				(width 0.1524)
				(type default)
			)
			(layer "F.SilkS")
		)
		(fp_line
			(start -0.207772 0.4064)
			(end -0.7874 0.4064)
			(stroke
				(width 0.1524)
				(type default)
			)
			(layer "F.SilkS")
		)
		(fp_line
			(start -0.7874 0.4064)
			(end -0.7874 -0.4064)
			(stroke
				(width 0.1524)
				(type default)
			)
			(layer "F.SilkS")
		)
		(fp_line
			(start -0.12065 -0.305054)
			(end -0.12065 -0.2794)
			(stroke
				(width 0.1)
				(type default)
			)
			(layer "F.Fab")
		)
		(fp_line
			(start -0.67945 -0.305054)
			(end -0.12065 -0.305054)
			(stroke
				(width 0.1)
				(type default)
			)
			(layer "F.Fab")
		)
		(fp_line
			(start 0.67945 -0.3048)
			(end 0.67945 0.3048)
			(stroke
				(width 0.1)
				(type default)
			)
			(layer "F.Fab")
		)
		(fp_line
			(start 0.12065 -0.3048)
			(end 0.67945 -0.3048)
			(stroke
				(width 0.1)
				(type default)
			)
			(layer "F.Fab")
		)
		(fp_line
			(start 0.12065 -0.2794)
			(end 0.12065 -0.3048)
			(stroke
				(width 0.1)
				(type default)
			)
			(layer "F.Fab")
		)
		(fp_line
			(start -0.12065 -0.2794)
			(end 0.12065 -0.2794)
			(stroke
				(width 0.1)
				(type default)
			)
			(layer "F.Fab")
		)
		(fp_line
			(start 0.120396 0.2794)
			(end -0.12065 0.2794)
			(stroke
				(width 0.1)
				(type default)
			)
			(layer "F.Fab")
		)
		(fp_line
			(start -0.12065 0.2794)
			(end -0.12065 0.3048)
			(stroke
				(width 0.1)
				(type default)
			)
			(layer "F.Fab")
		)
		(fp_line
			(start 0.67945 0.3048)
			(end 0.120396 0.3048)
			(stroke
				(width 0.1)
				(type default)
			)
			(layer "F.Fab")
		)
		(fp_line
			(start 0.120396 0.3048)
			(end 0.120396 0.2794)
			(stroke
				(width 0.1)
				(type default)
			)
			(layer "F.Fab")
		)
		(fp_line
			(start -0.12065 0.3048)
			(end -0.67945 0.3048)
			(stroke
				(width 0.1)
				(type default)
			)
			(layer "F.Fab")
		)
		(fp_line
			(start -0.67945 0.3048)
			(end -0.67945 -0.305054)
			(stroke
				(width 0.1)
				(type default)
			)
			(layer "F.Fab")
		)
		(pad "1" smd circle
			(at -0.40005 0 90)
			(size 0 0)
			(layers "F.Cu" "F.Mask" "F.Paste")
			(net "PVDDIO_P0_VCC1")
		)
		(pad "2" smd circle
			(at 0.40005 0 90)
			(size 0 0)
			(layers "F.Cu" "F.Mask" "F.Paste")
			(net "GND")
		)
	)
	(footprint ""
		(layer "F.Cu")
		(at 116.109496 -375.49963 -90)
		(property "Reference" "C1538"
			(at 0 0 270)
			(layer "F.SilkS")
			(hide yes)
			(effects
				(font
					(size 1.27 1.27)
				)
			)
		)
		(property "Value" ""
			(at 0 0 270)
			(layer "F.Fab")
			(effects
				(font
					(size 1.27 1.27)
				)
			)
		)
		(duplicate_pad_numbers_are_jumpers no)
		(fp_line
			(start -0.299974 0.150114)
			(end -0.299974 -0.150114)
			(stroke
				(width 0.1)
				(type default)
			)
			(layer "F.Fab")
		)
		(fp_line
			(start 0.299974 0.150114)
			(end -0.299974 0.150114)
			(stroke
				(width 0.1)
				(type default)
			)
			(layer "F.Fab")
		)
		(fp_line
			(start -0.299974 -0.150114)
			(end 0.299974 -0.150114)
			(stroke
				(width 0.1)
				(type default)
			)
			(layer "F.Fab")
		)
		(fp_line
			(start 0.299974 -0.150114)
			(end 0.299974 0.150114)
			(stroke
				(width 0.1)
				(type default)
			)
			(layer "F.Fab")
		)
		(pad "1" smd rect
			(at -0.2667 0 270)
			(size 0.3048 0.381)
			(layers "F.Cu" "F.Mask" "F.Paste")
			(net "P5E_CPU1_P3_TX_C_DN<4>")
		)
		(pad "2" smd rect
			(at 0.2667 0 270)
			(size 0.3048 0.381)
			(layers "F.Cu" "F.Mask" "F.Paste")
			(net "P5E_CPU1_P3_TX_DN<4>")
		)
	)
	(footprint ""
		(layer "F.Cu")
		(at 17.812258 -427.580298 90)
		(property "Reference" "R6170"
			(at 0 0 90)
			(layer "F.SilkS")
			(hide yes)
			(effects
				(font
					(size 1.27 1.27)
				)
			)
		)
		(property "Value" ""
			(at 0 0 90)
			(layer "F.Fab")
			(effects
				(font
					(size 1.27 1.27)
				)
			)
		)
		(duplicate_pad_numbers_are_jumpers no)
		(fp_line
			(start 0.7874 -0.4064)
			(end 0.7874 0.4064)
			(stroke
				(width 0.1524)
				(type default)
			)
			(layer "F.SilkS")
		)
		(fp_line
			(start -0.7874 -0.4064)
			(end 0.7874 -0.4064)
			(stroke
				(width 0.1524)
				(type default)
			)
			(layer "F.SilkS")
		)
		(fp_line
			(start 0.7874 0.4064)
			(end -0.7874 0.4064)
			(stroke
				(width 0.1524)
				(type default)
			)
			(layer "F.SilkS")
		)
		(fp_line
			(start -0.7874 0.4064)
			(end -0.7874 -0.4064)
			(stroke
				(width 0.1524)
				(type default)
			)
			(layer "F.SilkS")
		)
		(fp_line
			(start -0.12065 -0.305054)
			(end -0.12065 -0.2794)
			(stroke
				(width 0.1)
				(type default)
			)
			(layer "F.Fab")
		)
		(fp_line
			(start -0.67945 -0.305054)
			(end -0.12065 -0.305054)
			(stroke
				(width 0.1)
				(type default)
			)
			(layer "F.Fab")
		)
		(fp_line
			(start 0.67945 -0.3048)
			(end 0.67945 0.3048)
			(stroke
				(width 0.1)
				(type default)
			)
			(layer "F.Fab")
		)
		(fp_line
			(start 0.12065 -0.3048)
			(end 0.67945 -0.3048)
			(stroke
				(width 0.1)
				(type default)
			)
			(layer "F.Fab")
		)
		(fp_line
			(start 0.12065 -0.2794)
			(end 0.12065 -0.3048)
			(stroke
				(width 0.1)
				(type default)
			)
			(layer "F.Fab")
		)
		(fp_line
			(start -0.12065 -0.2794)
			(end 0.12065 -0.2794)
			(stroke
				(width 0.1)
				(type default)
			)
			(layer "F.Fab")
		)
		(fp_line
			(start 0.120396 0.2794)
			(end -0.12065 0.2794)
			(stroke
				(width 0.1)
				(type default)
			)
			(layer "F.Fab")
		)
		(fp_line
			(start -0.12065 0.2794)
			(end -0.12065 0.3048)
			(stroke
				(width 0.1)
				(type default)
			)
			(layer "F.Fab")
		)
		(fp_line
			(start 0.67945 0.3048)
			(end 0.120396 0.3048)
			(stroke
				(width 0.1)
				(type default)
			)
			(layer "F.Fab")
		)
		(fp_line
			(start 0.120396 0.3048)
			(end 0.120396 0.2794)
			(stroke
				(width 0.1)
				(type default)
			)
			(layer "F.Fab")
		)
		(fp_line
			(start -0.12065 0.3048)
			(end -0.67945 0.3048)
			(stroke
				(width 0.1)
				(type default)
			)
			(layer "F.Fab")
		)
		(fp_line
			(start -0.67945 0.3048)
			(end -0.67945 -0.305054)
			(stroke
				(width 0.1)
				(type default)
			)
			(layer "F.Fab")
		)
		(pad "1" smd circle
			(at -0.40005 0 90)
			(size 0 0)
			(layers "F.Cu" "F.Mask" "F.Paste")
			(net "FM_P2E_BUF2_VODA_DB")
		)
		(pad "2" smd circle
			(at 0.40005 0 90)
			(size 0 0)
			(layers "F.Cu" "F.Mask" "F.Paste")
			(net "GND")
		)
	)
)
